(kicad_pcb
	(version 20260206)
	(generator "pcbnew")
	(generator_version "10.0")
	(general
		(thickness 1.6)
		(legacy_teardrops no)
	)
	(paper "A4")
	(title_block
		(title "netronome-mezz — pcbd0082-001_rev01_jul9_a.brd")
		(comment 1 "Open CloudServer (Microsoft) / footprints 148-156 of 714")
	)
	(layers
		(0 "F.Cu" signal "TOP")
		(4 "In1.Cu" signal "02_GND")
		(6 "In2.Cu" signal "03_SIG")
		(8 "In3.Cu" signal "04_SIG")
		(10 "In4.Cu" signal "05_GND")
		(12 "In5.Cu" signal "06_PWR1")
		(14 "In6.Cu" signal "07_SIG")
		(16 "In7.Cu" signal "08_SIG")
		(18 "In8.Cu" signal "09_GND")
		(2 "B.Cu" signal "BOTTOM")
		(9 "F.Adhes" user "F.Adhesive")
		(11 "B.Adhes" user "B.Adhesive")
		(13 "F.Paste" user "Package Geometry/Pastemask Top")
		(15 "B.Paste" user "Package Geometry/Pastemask Bottom")
		(5 "F.SilkS" user "Ref Des/Silkscreen Top")
		(7 "B.SilkS" user "Ref Des/Silkscreen Bottom")
		(1 "F.Mask" user "Board Geometry/Soldermask Top")
		(3 "B.Mask" user "Board Geometry/Soldermask Bottom")
		(17 "Dwgs.User" user "User.Drawings")
		(19 "Cmts.User" user "User.Comments")
		(21 "Eco1.User" user "User.Eco1")
		(23 "Eco2.User" user "User.Eco2")
		(25 "Edge.Cuts" user "Board Geometry/Outline")
		(27 "Margin" user)
		(31 "F.CrtYd" user "Package Geometry/Place Bound Top")
		(29 "B.CrtYd" user "Package Geometry/Place Bound Bottom")
		(35 "F.Fab" user "Ref Des/Assembly Top")
		(33 "B.Fab" user "Ref Des/Assembly Bottom")
		(45 "User.4" user "COMPVAL_TYPE_BOTTOM")
	)
	(footprint ""
		(layer "F.Cu")
		(at 39.624 43.307)
		(property "Reference" "C61"
			(at 1.29667 -1.27 90)
			(unlocked yes)
			(layer "F.SilkS")
			(effects
				(font
					(size 0.7874 0.5842)
					(thickness 0.127)
				)
				(justify left)
			)
		)
		(property "Value" "100UF"
			(at -0.78232 0.4826 90)
			(unlocked yes)
			(layer "F.Fab")
			(hide yes)
			(effects
				(font
					(size 1.27 0.9652)
					(thickness 0.000001)
				)
				(justify left)
			)
		)
		(property "Device Type" "CAPC0087"
			(at -0.78232 0.4826 90)
			(unlocked yes)
			(layer "F.Fab")
			(hide yes)
			(effects
				(font
					(size 1.27 0.9652)
					(thickness 0.000001)
				)
				(justify left)
			)
		)
		(duplicate_pad_numbers_are_jumpers no)
		(fp_circle
			(center 0 0)
			(end 0.508 0)
			(stroke
				(width 0.2032)
				(type default)
			)
			(fill no)
			(layer "F.SilkS")
		)
		(fp_circle
			(center 0 0)
			(end 0.508 0)
			(stroke
				(width 0.2032)
				(type default)
			)
			(fill no)
			(layer "F.SilkS")
		)
		(fp_poly
			(pts
				(xy -1.27 2.9464) (xy 1.27 2.9464) (xy 1.27 -2.9464) (xy -1.27 -2.9464)
			)
			(stroke
				(width 0)
				(type default)
			)
			(fill no)
			(layer "F.CrtYd")
		)
		(fp_line
			(start -1.016 -2.794)
			(end 1.016 -2.794)
			(stroke
				(width 0.0254)
				(type default)
			)
			(layer "F.Fab")
		)
		(fp_line
			(start -1.016 2.794)
			(end -1.016 -2.794)
			(stroke
				(width 0.0254)
				(type default)
			)
			(layer "F.Fab")
		)
		(fp_line
			(start 1.016 -2.794)
			(end 1.016 2.794)
			(stroke
				(width 0.0254)
				(type default)
			)
			(layer "F.Fab")
		)
		(fp_line
			(start 1.016 2.794)
			(end -1.016 2.794)
			(stroke
				(width 0.0254)
				(type default)
			)
			(layer "F.Fab")
		)
		(pad "1" smd rect
			(at 0 -1.6764)
			(size 1.524 1.524)
			(layers "F.Cu" "F.Mask" "F.Paste")
			(net "VDD_CORE")
		)
		(pad "2" smd rect
			(at 0 1.6764)
			(size 1.524 1.524)
			(layers "F.Cu" "F.Mask" "F.Paste")
			(net "GND")
		)
		(zone
			(layer "F.Cu")
			(hatch none 0.5)
			(connect_pads
				(clearance 0)
			)
			(min_thickness 0.25)
			(keepout
				(tracks not_allowed)
				(vias allowed)
				(pads allowed)
				(copperpour not_allowed)
				(footprints allowed)
			)
			(placement
				(enabled no)
				(sheetname "")
			)
			(fill
				(thermal_gap 0.5)
				(thermal_bridge_width 0.5)
				(island_removal_mode 0)
			)
			(polygon
				(pts
					(xy 38.8366 42.418) (xy 40.4114 42.418) (xy 40.4114 42.5704) (xy 38.8366 42.5704)
				)
			)
		)
		(zone
			(layer "F.Cu")
			(hatch none 0.5)
			(connect_pads
				(clearance 0)
			)
			(min_thickness 0.25)
			(keepout
				(tracks not_allowed)
				(vias allowed)
				(pads allowed)
				(copperpour not_allowed)
				(footprints allowed)
			)
			(placement
				(enabled no)
				(sheetname "")
			)
			(fill
				(thermal_gap 0.5)
				(thermal_bridge_width 0.5)
				(island_removal_mode 0)
			)
			(polygon
				(pts
					(xy 38.8366 44.0436) (xy 40.4114 44.0436) (xy 40.4114 44.196) (xy 38.8366 44.196)
				)
			)
		)
		(zone
			(layer "F.Cu")
			(hatch none 0.5)
			(connect_pads
				(clearance 0)
			)
			(min_thickness 0.25)
			(keepout
				(tracks allowed)
				(vias not_allowed)
				(pads allowed)
				(copperpour not_allowed)
				(footprints allowed)
			)
			(placement
				(enabled no)
				(sheetname "")
			)
			(fill
				(thermal_gap 0.5)
				(thermal_bridge_width 0.5)
				(island_removal_mode 0)
			)
			(polygon
				(pts
					(xy 38.8366 44.9072) (xy 40.4114 44.9072) (xy 40.4114 41.7068) (xy 38.8366 41.7068)
				)
			)
		)
	)
	(footprint ""
		(layer "F.Cu")
		(at 73.851008 17.455998)
		(property "Reference" "V_A-DQS3-P"
			(at 0 0 0)
			(layer "F.SilkS")
			(hide yes)
			(effects
				(font
					(size 1.27 1.27)
				)
			)
		)
		(property "Value" ""
			(at 0 0 0)
			(layer "F.Fab")
			(effects
				(font
					(size 1.27 1.27)
				)
			)
		)
		(duplicate_pad_numbers_are_jumpers no)
		(pad "1" thru_hole circle
			(at 0 0)
			(size 0.762 0.762)
			(drill 0.20574)
			(layers "*.Cu" "*.Mask")
			(remove_unused_layers no)
			(net "DDR0_32A_DQS3_P")
			(clearance 0.127)
			(thermal_gap 0.127)
			(padstack
				(mode front_inner_back)
				(layer "Inner"
					(shape circle)
					(size 0.4572 0.4572)
					(clearance 0.1143)
				)
				(layer "B.Cu"
					(shape circle)
					(size 0.4572 0.4572)
					(clearance 0.1143)
				)
			)
		)
	)
	(footprint ""
		(layer "F.Cu")
		(at 30.226 45.72 90)
		(property "Reference" "R313"
			(at -3.302 0.53467 90)
			(unlocked yes)
			(layer "F.SilkS")
			(effects
				(font
					(size 0.7874 0.5842)
					(thickness 0.127)
				)
				(justify left)
			)
		)
		(property "Value" "1.0K"
			(at -0.148158 1.3462 180)
			(unlocked yes)
			(layer "F.Fab")
			(hide yes)
			(effects
				(font
					(size 1.27 0.9652)
					(thickness 0.000001)
				)
				(justify left)
			)
		)
		(property "Device Type" "REST0025"
			(at -0.148158 1.3462 180)
			(unlocked yes)
			(layer "F.Fab")
			(hide yes)
			(effects
				(font
					(size 1.27 0.9652)
					(thickness 0.000001)
				)
				(justify left)
			)
		)
		(duplicate_pad_numbers_are_jumpers no)
		(fp_poly
			(pts
				(xy 0.635 1.0668) (xy 0.635 -1.0668) (xy -0.635 -1.0668) (xy -0.635 1.0668)
			)
			(stroke
				(width 0)
				(type default)
			)
			(fill no)
			(layer "F.CrtYd")
		)
		(fp_line
			(start 0.254 -0.508)
			(end 0.254 0.508)
			(stroke
				(width 0.0254)
				(type default)
			)
			(layer "F.Fab")
		)
		(fp_line
			(start -0.254 -0.508)
			(end 0.254 -0.508)
			(stroke
				(width 0.0254)
				(type default)
			)
			(layer "F.Fab")
		)
		(fp_line
			(start 0.254 0.508)
			(end -0.254 0.508)
			(stroke
				(width 0.0254)
				(type default)
			)
			(layer "F.Fab")
		)
		(fp_line
			(start -0.254 0.508)
			(end -0.254 -0.508)
			(stroke
				(width 0.0254)
				(type default)
			)
			(layer "F.Fab")
		)
		(pad "1" smd rect
			(at 0 -0.4191 90)
			(size 0.508 0.5334)
			(layers "F.Cu" "F.Mask" "F.Paste")
			(net "10N2504")
		)
		(pad "2" smd rect
			(at 0 0.4191 90)
			(size 0.508 0.5334)
			(layers "F.Cu" "F.Mask" "F.Paste")
			(net "NFP_VDD_CORE_SENSE_VDD")
		)
		(zone
			(layer "F.Cu")
			(hatch none 0.5)
			(connect_pads
				(clearance 0)
			)
			(min_thickness 0.25)
			(keepout
				(tracks not_allowed)
				(vias allowed)
				(pads allowed)
				(copperpour not_allowed)
				(footprints allowed)
			)
			(placement
				(enabled no)
				(sheetname "")
			)
			(fill
				(thermal_gap 0.5)
				(thermal_bridge_width 0.5)
				(island_removal_mode 0)
			)
			(polygon
				(pts
					(xy 30.2006 45.6946) (xy 30.2514 45.6946) (xy 30.2514 45.7454) (xy 30.2006 45.7454)
				)
			)
		)
	)
	(footprint ""
		(layer "F.Cu")
		(at 33.782 44.323 180)
		(property "Reference" "R13"
			(at 1.27 -0.91567 0)
			(unlocked yes)
			(layer "F.SilkS")
			(effects
				(font
					(size 0.7874 0.5842)
					(thickness 0.127)
				)
				(justify left)
			)
		)
		(property "Value" ""
			(at 0 0 180)
			(layer "F.Fab")
			(effects
				(font
					(size 1.27 1.27)
				)
			)
		)
		(duplicate_pad_numbers_are_jumpers no)
		(fp_line
			(start 0.0254 0.127)
			(end -0.0254 0.127)
			(stroke
				(width 0.1016)
				(type default)
			)
			(layer "F.SilkS")
		)
		(fp_line
			(start 0.0254 -0.127)
			(end 0.0254 0.127)
			(stroke
				(width 0.1016)
				(type default)
			)
			(layer "F.SilkS")
		)
		(fp_line
			(start -0.0254 0.127)
			(end -0.0254 -0.127)
			(stroke
				(width 0.1016)
				(type default)
			)
			(layer "F.SilkS")
		)
		(fp_line
			(start -0.0254 -0.127)
			(end 0.0254 -0.127)
			(stroke
				(width 0.1016)
				(type default)
			)
			(layer "F.SilkS")
		)
		(fp_poly
			(pts
				(xy 0.889 -0.4953) (xy 0.889 0.4953) (xy -0.889 0.4953) (xy -0.889 -0.4953)
			)
			(stroke
				(width 0)
				(type default)
			)
			(fill no)
			(layer "F.CrtYd")
		)
		(fp_line
			(start 0.508 0.254)
			(end 0.508 -0.254)
			(stroke
				(width 0.0254)
				(type default)
			)
			(layer "F.Fab")
		)
		(fp_line
			(start 0.508 -0.254)
			(end -0.508 -0.254)
			(stroke
				(width 0.0254)
				(type default)
			)
			(layer "F.Fab")
		)
		(fp_line
			(start -0.508 0.254)
			(end 0.508 0.254)
			(stroke
				(width 0.0254)
				(type default)
			)
			(layer "F.Fab")
		)
		(fp_line
			(start -0.508 -0.254)
			(end -0.508 0.254)
			(stroke
				(width 0.0254)
				(type default)
			)
			(layer "F.Fab")
		)
		(pad "1" smd rect
			(at -0.4699 0 180)
			(size 0.5334 0.508)
			(layers "F.Cu" "F.Mask" "F.Paste")
			(net "NFP_VDD_CORE_TCOMPB")
		)
		(pad "2" smd rect
			(at 0.4699 0 180)
			(size 0.5334 0.508)
			(layers "F.Cu" "F.Mask" "F.Paste")
			(net "10N2528")
		)
	)
	(footprint ""
		(layer "F.Cu")
		(at 85.344 35.306)
		(property "Reference" "TP65"
			(at 1.67767 1.016 90)
			(unlocked yes)
			(layer "F.SilkS")
			(effects
				(font
					(size 0.7874 0.5842)
					(thickness 0.127)
				)
				(justify left)
			)
		)
		(property "Value" "*"
			(at -0.4826 -0.14732 0)
			(unlocked yes)
			(layer "F.Fab")
			(hide yes)
			(effects
				(font
					(size 1.27 0.9652)
					(thickness 0.000001)
				)
				(justify left)
			)
		)
		(property "Device Type" "TP_SMALL"
			(at -0.4826 -0.14732 0)
			(unlocked yes)
			(layer "F.Fab")
			(hide yes)
			(effects
				(font
					(size 1.27 0.9652)
					(thickness 0.000001)
				)
				(justify left)
			)
		)
		(duplicate_pad_numbers_are_jumpers no)
		(fp_line
			(start -0.8636 -0.8636)
			(end -0.8636 0.8636)
			(stroke
				(width 0.1524)
				(type default)
			)
			(layer "F.SilkS")
		)
		(fp_line
			(start -0.8636 0.8636)
			(end 0.8636 0.8636)
			(stroke
				(width 0.1524)
				(type default)
			)
			(layer "F.SilkS")
		)
		(fp_line
			(start 0.8636 -0.8636)
			(end -0.8636 -0.8636)
			(stroke
				(width 0.1524)
				(type default)
			)
			(layer "F.SilkS")
		)
		(fp_line
			(start 0.8636 0.8636)
			(end 0.8636 -0.8636)
			(stroke
				(width 0.1524)
				(type default)
			)
			(layer "F.SilkS")
		)
		(fp_poly
			(pts
				(xy -0.635 -0.635) (xy -0.635 0.635) (xy 0.635 0.635) (xy 0.635 -0.635)
			)
			(stroke
				(width 0)
				(type default)
			)
			(fill no)
			(layer "F.CrtYd")
		)
		(pad "1" smd rect
			(at 0 0)
			(size 1.27 1.27)
			(layers "F.Cu" "F.Mask" "F.Paste")
			(net "VDDQ_VTT_EN")
		)
	)
	(footprint ""
		(layer "F.Cu")
		(at 13.208 30.607)
		(property "Reference" "TP42"
			(at -1.75133 1.016 90)
			(unlocked yes)
			(layer "F.SilkS")
			(effects
				(font
					(size 0.7874 0.5842)
					(thickness 0.127)
				)
				(justify left)
			)
		)
		(property "Value" "*"
			(at -0.4826 -0.14732 0)
			(unlocked yes)
			(layer "F.Fab")
			(hide yes)
			(effects
				(font
					(size 1.27 0.9652)
					(thickness 0.000001)
				)
				(justify left)
			)
		)
		(property "Device Type" "TP_SMALL"
			(at -0.4826 -0.14732 0)
			(unlocked yes)
			(layer "F.Fab")
			(hide yes)
			(effects
				(font
					(size 1.27 0.9652)
					(thickness 0.000001)
				)
				(justify left)
			)
		)
		(duplicate_pad_numbers_are_jumpers no)
		(fp_line
			(start -0.8636 -0.8636)
			(end -0.8636 0.8636)
			(stroke
				(width 0.1524)
				(type default)
			)
			(layer "F.SilkS")
		)
		(fp_line
			(start -0.8636 0.8636)
			(end 0.8636 0.8636)
			(stroke
				(width 0.1524)
				(type default)
			)
			(layer "F.SilkS")
		)
		(fp_line
			(start 0.8636 -0.8636)
			(end -0.8636 -0.8636)
			(stroke
				(width 0.1524)
				(type default)
			)
			(layer "F.SilkS")
		)
		(fp_line
			(start 0.8636 0.8636)
			(end 0.8636 -0.8636)
			(stroke
				(width 0.1524)
				(type default)
			)
			(layer "F.SilkS")
		)
		(fp_poly
			(pts
				(xy -0.635 -0.635) (xy -0.635 0.635) (xy 0.635 0.635) (xy 0.635 -0.635)
			)
			(stroke
				(width 0)
				(type default)
			)
			(fill no)
			(layer "F.CrtYd")
		)
		(pad "1" smd rect
			(at 0 0)
			(size 1.27 1.27)
			(layers "F.Cu" "F.Mask" "F.Paste")
			(net "VDD_5.0V")
		)
	)
	(footprint ""
		(layer "F.Cu")
		(at 18.0594 40.894 90)
		(property "Reference" "C132"
			(at 0.98933 -1.2954 0)
			(unlocked yes)
			(layer "F.SilkS")
			(effects
				(font
					(size 0.7874 0.5842)
					(thickness 0.127)
				)
				(justify left)
			)
		)
		(property "Value" "10UF"
			(at -0.148158 1.7526 180)
			(unlocked yes)
			(layer "F.Fab")
			(hide yes)
			(effects
				(font
					(size 1.27 0.9652)
					(thickness 0.000001)
				)
				(justify left)
			)
		)
		(property "Device Type" "CAPC0058"
			(at -0.148158 1.7526 180)
			(unlocked yes)
			(layer "F.Fab")
			(hide yes)
			(effects
				(font
					(size 1.27 0.9652)
					(thickness 0.000001)
				)
				(justify left)
			)
		)
		(duplicate_pad_numbers_are_jumpers no)
		(fp_circle
			(center 0 0)
			(end 0 0.127)
			(stroke
				(width 0.2032)
				(type default)
			)
			(fill no)
			(layer "F.SilkS")
		)
		(fp_poly
			(pts
				(xy 0.7874 -1.6637) (xy -0.7874 -1.6637) (xy -0.7874 1.6637) (xy 0.7874 1.6637)
			)
			(stroke
				(width 0)
				(type default)
			)
			(fill no)
			(layer "F.CrtYd")
		)
		(fp_line
			(start 0.4064 -0.7874)
			(end 0.4064 0.8128)
			(stroke
				(width 0.0254)
				(type default)
			)
			(layer "F.Fab")
		)
		(fp_line
			(start -0.4064 -0.7874)
			(end 0.4064 -0.7874)
			(stroke
				(width 0.0254)
				(type default)
			)
			(layer "F.Fab")
		)
		(fp_line
			(start 0.4064 0.8128)
			(end -0.4064 0.8128)
			(stroke
				(width 0.0254)
				(type default)
			)
			(layer "F.Fab")
		)
		(fp_line
			(start -0.4064 0.8128)
			(end -0.4064 -0.7874)
			(stroke
				(width 0.0254)
				(type default)
			)
			(layer "F.Fab")
		)
		(pad "1" smd rect
			(at 0 -0.8001 90)
			(size 0.8636 0.9652)
			(layers "F.Cu" "F.Mask" "F.Paste")
			(net "VDD_5.0V")
		)
		(pad "2" smd rect
			(at 0 0.8001 90)
			(size 0.8636 0.9652)
			(layers "F.Cu" "F.Mask" "F.Paste")
			(net "GND")
		)
	)
	(footprint ""
		(layer "F.Cu")
		(at 24.511 16.8529)
		(property "Reference" "R23"
			(at 0 0 0)
			(layer "F.SilkS")
			(hide yes)
			(effects
				(font
					(size 1.27 1.27)
				)
			)
		)
		(property "Value" "4.75K"
			(at -0.148158 1.3462 90)
			(unlocked yes)
			(layer "F.Fab")
			(hide yes)
			(effects
				(font
					(size 1.27 0.9652)
					(thickness 0.000001)
				)
				(justify left)
			)
		)
		(property "Device Type" "REST4024"
			(at -0.148158 1.3462 90)
			(unlocked yes)
			(layer "F.Fab")
			(hide yes)
			(effects
				(font
					(size 1.27 0.9652)
					(thickness 0.000001)
				)
				(justify left)
			)
		)
		(duplicate_pad_numbers_are_jumpers no)
		(fp_poly
			(pts
				(xy 0.635 1.0668) (xy 0.635 -1.0668) (xy -0.635 -1.0668) (xy -0.635 1.0668)
			)
			(stroke
				(width 0)
				(type default)
			)
			(fill no)
			(layer "F.CrtYd")
		)
		(fp_line
			(start -0.254 -0.508)
			(end 0.254 -0.508)
			(stroke
				(width 0.0254)
				(type default)
			)
			(layer "F.Fab")
		)
		(fp_line
			(start -0.254 0.508)
			(end -0.254 -0.508)
			(stroke
				(width 0.0254)
				(type default)
			)
			(layer "F.Fab")
		)
		(fp_line
			(start 0.254 -0.508)
			(end 0.254 0.508)
			(stroke
				(width 0.0254)
				(type default)
			)
			(layer "F.Fab")
		)
		(fp_line
			(start 0.254 0.508)
			(end -0.254 0.508)
			(stroke
				(width 0.0254)
				(type default)
			)
			(layer "F.Fab")
		)
		(pad "1" smd rect
			(at 0 -0.4191)
			(size 0.508 0.5334)
			(layers "F.Cu" "F.Mask" "F.Paste")
			(net "VDD_3.3V")
		)
		(pad "2" smd rect
			(at 0 0.4191)
			(size 0.508 0.5334)
			(layers "F.Cu" "F.Mask" "F.Paste")
			(net "NFP_ARM_SPI_FLASH_MOSI")
		)
		(zone
			(layer "F.Cu")
			(hatch none 0.5)
			(connect_pads
				(clearance 0)
			)
			(min_thickness 0.25)
			(keepout
				(tracks not_allowed)
				(vias allowed)
				(pads allowed)
				(copperpour not_allowed)
				(footprints allowed)
			)
			(placement
				(enabled no)
				(sheetname "")
			)
			(fill
				(thermal_gap 0.5)
				(thermal_bridge_width 0.5)
				(island_removal_mode 0)
			)
			(polygon
				(pts
					(xy 24.5364 16.8275) (xy 24.5364 16.8783) (xy 24.4856 16.8783) (xy 24.4856 16.8275)
				)
			)
		)
	)
	(footprint ""
		(layer "F.Cu")
		(at 1.524 34.163 180)
		(property "Reference" "R100"
			(at 0 0 180)
			(layer "F.SilkS")
			(hide yes)
			(effects
				(font
					(size 1.27 1.27)
				)
			)
		)
		(property "Value" "4.75K"
			(at -0.148158 1.3462 270)
			(unlocked yes)
			(layer "F.Fab")
			(hide yes)
			(effects
				(font
					(size 1.27 0.9652)
					(thickness 0.000001)
				)
				(justify left)
			)
		)
		(property "Device Type" "REST4024"
			(at -0.148158 1.3462 270)
			(unlocked yes)
			(layer "F.Fab")
			(hide yes)
			(effects
				(font
					(size 1.27 0.9652)
					(thickness 0.000001)
				)
				(justify left)
			)
		)
		(duplicate_pad_numbers_are_jumpers no)
		(fp_poly
			(pts
				(xy 0.635 1.0668) (xy 0.635 -1.0668) (xy -0.635 -1.0668) (xy -0.635 1.0668)
			)
			(stroke
				(width 0)
				(type default)
			)
			(fill no)
			(layer "F.CrtYd")
		)
		(fp_line
			(start 0.254 0.508)
			(end -0.254 0.508)
			(stroke
				(width 0.0254)
				(type default)
			)
			(layer "F.Fab")
		)
		(fp_line
			(start 0.254 -0.508)
			(end 0.254 0.508)
			(stroke
				(width 0.0254)
				(type default)
			)
			(layer "F.Fab")
		)
		(fp_line
			(start -0.254 0.508)
			(end -0.254 -0.508)
			(stroke
				(width 0.0254)
				(type default)
			)
			(layer "F.Fab")
		)
		(fp_line
			(start -0.254 -0.508)
			(end 0.254 -0.508)
			(stroke
				(width 0.0254)
				(type default)
			)
			(layer "F.Fab")
		)
		(pad "1" smd rect
			(at 0 -0.4191 180)
			(size 0.508 0.5334)
			(layers "F.Cu" "F.Mask" "F.Paste")
			(net "VDD_7401_PGOOD")
		)
		(pad "2" smd rect
			(at 0 0.4191 180)
			(size 0.508 0.5334)
			(layers "F.Cu" "F.Mask" "F.Paste")
			(net "EXT_3.3V")
		)
		(zone
			(layer "F.Cu")
			(hatch none 0.5)
			(connect_pads
				(clearance 0)
			)
			(min_thickness 0.25)
			(keepout
				(tracks not_allowed)
				(vias allowed)
				(pads allowed)
				(copperpour not_allowed)
				(footprints allowed)
			)
			(placement
				(enabled no)
				(sheetname "")
			)
			(fill
				(thermal_gap 0.5)
				(thermal_bridge_width 0.5)
				(island_removal_mode 0)
			)
			(polygon
				(pts
					(xy 1.4986 34.1884) (xy 1.4986 34.1376) (xy 1.5494 34.1376) (xy 1.5494 34.1884)
				)
			)
		)
	)
)
